# T6G (Grand Teton) — schematic netlist excerpt (pin names and nets, part order shuffled) for the footprints in the layout excerpt that follows; sources: Cadence DE-HDL packaged netlist, KiCad conversion of 04192023_DAF0TMB3IC0_F0TG_MB_C_brd_V02_OCP.brd

PR306  Q_RES  0 5% CHIP  pkg 0402LF  page 193 : A = VSENSE_PVDDCR_CPU0_P0_DP ; B = VSENSE_PVDDCR_CPU0_P0_VSEN0
PC226  Q_CAPP  470UF 2.5V 20% SPCAP  pkg SMLF  page 208 : A = PVDD11_S3_P0 ; B = GND

(kicad_pcb
	(version 20260206)
	(generator "pcbnew")
	(generator_version "10.0")
	(general
		(thickness 1.6)
		(legacy_teardrops no)
	)
	(paper "A4")
	(title_block
		(title "04192023_DAF0TMB3IC0_F0TG_MB_C_brd_V02_OCP.brd")
		(comment 1 "Grand Teton / footprints 6152-6153 of 8354")
	)
	(layers
		(0 "F.Cu" signal "TOP")
		(4 "In1.Cu" signal "GND")
		(6 "In2.Cu" signal "IN1")
		(8 "In3.Cu" signal "GND1")
		(10 "In4.Cu" signal "IN2")
		(12 "In5.Cu" signal "GND2")
		(14 "In6.Cu" signal "IN3")
		(16 "In7.Cu" signal "GND3")
		(18 "In8.Cu" signal "VCC")
		(20 "In9.Cu" signal "VCC1")
		(22 "In10.Cu" signal "GND4")
		(24 "In11.Cu" signal "IN4")
		(26 "In12.Cu" signal "GND5")
		(28 "In13.Cu" signal "IN5")
		(30 "In14.Cu" signal "GND6")
		(32 "In15.Cu" signal "IN6")
		(34 "In16.Cu" signal "GND7")
		(2 "B.Cu" signal "BOTTOM")
		(9 "F.Adhes" user "F.Adhesive")
		(11 "B.Adhes" user "B.Adhesive")
		(13 "F.Paste" user "Package Geometry/Pastemask Top")
		(15 "B.Paste" user "Package Geometry/Pastemask Bottom")
		(5 "F.SilkS" user "Ref Des/Silkscreen Top")
		(7 "B.SilkS" user "Ref Des/Silkscreen Bottom")
		(1 "F.Mask" user "Board Geometry/Soldermask Top")
		(3 "B.Mask" user "Board Geometry/Soldermask Bottom")
		(17 "Dwgs.User" user "User.Drawings")
		(19 "Cmts.User" user "User.Comments")
		(21 "Eco1.User" user "User.Eco1")
		(23 "Eco2.User" user "User.Eco2")
		(25 "Edge.Cuts" user "Board Geometry/Outline")
		(27 "Margin" user)
		(31 "F.CrtYd" user "Package Geometry/Place Bound Top")
		(29 "B.CrtYd" user "Package Geometry/Place Bound Bottom")
		(35 "F.Fab" user "Ref Des/Assembly Top")
		(33 "B.Fab" user "Ref Des/Assembly Bottom")
	)
	(footprint ""
		(layer "B.Cu")
		(at 374.770142 -149.055582 90)
		(property "Reference" "PR306"
			(at 0 0 90)
			(layer "B.SilkS")
			(hide yes)
			(effects
				(font
					(size 1.27 1.27)
				)
				(justify mirror)
			)
		)
		(property "Value" ""
			(at 0 0 90)
			(layer "B.Fab")
			(effects
				(font
					(size 1.27 1.27)
				)
				(justify mirror)
			)
		)
		(duplicate_pad_numbers_are_jumpers no)
		(fp_line
			(start 0.7874 -0.4064)
			(end -0.7874 -0.4064)
			(stroke
				(width 0.1524)
				(type default)
			)
			(layer "B.SilkS")
		)
		(fp_line
			(start -0.7874 -0.4064)
			(end -0.7874 0.4064)
			(stroke
				(width 0.1524)
				(type default)
			)
			(layer "B.SilkS")
		)
		(fp_line
			(start 0.7874 0.4064)
			(end 0.7874 -0.4064)
			(stroke
				(width 0.1524)
				(type default)
			)
			(layer "B.SilkS")
		)
		(fp_line
			(start -0.7874 0.4064)
			(end 0.7874 0.4064)
			(stroke
				(width 0.1524)
				(type default)
			)
			(layer "B.SilkS")
		)
		(fp_line
			(start 0.67945 -0.305054)
			(end 0.12065 -0.305054)
			(stroke
				(width 0.1)
				(type default)
			)
			(layer "B.Fab")
		)
		(fp_line
			(start 0.12065 -0.305054)
			(end 0.12065 -0.2794)
			(stroke
				(width 0.1)
				(type default)
			)
			(layer "B.Fab")
		)
		(fp_line
			(start -0.12065 -0.3048)
			(end -0.67945 -0.3048)
			(stroke
				(width 0.1)
				(type default)
			)
			(layer "B.Fab")
		)
		(fp_line
			(start -0.67945 -0.3048)
			(end -0.67945 0.3048)
			(stroke
				(width 0.1)
				(type default)
			)
			(layer "B.Fab")
		)
		(fp_line
			(start 0.12065 -0.2794)
			(end -0.12065 -0.2794)
			(stroke
				(width 0.1)
				(type default)
			)
			(layer "B.Fab")
		)
		(fp_line
			(start -0.12065 -0.2794)
			(end -0.12065 -0.3048)
			(stroke
				(width 0.1)
				(type default)
			)
			(layer "B.Fab")
		)
		(fp_line
			(start 0.12065 0.2794)
			(end 0.12065 0.3048)
			(stroke
				(width 0.1)
				(type default)
			)
			(layer "B.Fab")
		)
		(fp_line
			(start -0.120396 0.2794)
			(end 0.12065 0.2794)
			(stroke
				(width 0.1)
				(type default)
			)
			(layer "B.Fab")
		)
		(fp_line
			(start 0.67945 0.3048)
			(end 0.67945 -0.305054)
			(stroke
				(width 0.1)
				(type default)
			)
			(layer "B.Fab")
		)
		(fp_line
			(start 0.12065 0.3048)
			(end 0.67945 0.3048)
			(stroke
				(width 0.1)
				(type default)
			)
			(layer "B.Fab")
		)
		(fp_line
			(start -0.120396 0.3048)
			(end -0.120396 0.2794)
			(stroke
				(width 0.1)
				(type default)
			)
			(layer "B.Fab")
		)
		(fp_line
			(start -0.67945 0.3048)
			(end -0.120396 0.3048)
			(stroke
				(width 0.1)
				(type default)
			)
			(layer "B.Fab")
		)
		(pad "1" smd circle
			(at 0.40005 0 270)
			(size 0 0)
			(layers "B.Cu" "B.Mask" "B.Paste")
			(net "VSENSE_PVDDCR_CPU0_P0_DP")
		)
		(pad "2" smd circle
			(at -0.40005 0 270)
			(size 0 0)
			(layers "B.Cu" "B.Mask" "B.Paste")
			(net "VSENSE_PVDDCR_CPU0_P0_VSEN0")
		)
	)
	(footprint ""
		(layer "B.Cu")
		(at 431.918618 -344.006932 -90)
		(property "Reference" "PC226"
			(at 7.654036 -3.431286 270)
			(unlocked yes)
			(layer "B.SilkS")
			(effects
				(font
					(size 0.7874 0.5842)
					(thickness 0.1524)
				)
				(justify left mirror)
			)
		)
		(property "Value" ""
			(at 0 0 90)
			(layer "B.Fab")
			(effects
				(font
					(size 1.27 1.27)
				)
				(justify mirror)
			)
		)
		(duplicate_pad_numbers_are_jumpers no)
		(fp_line
			(start -4.533392 2.249932)
			(end 4.533392 2.249932)
			(stroke
				(width 0.1524)
				(type default)
			)
			(layer "B.SilkS")
		)
		(fp_line
			(start 4.533392 2.249932)
			(end 4.533392 -2.249932)
			(stroke
				(width 0.1524)
				(type default)
			)
			(layer "B.SilkS")
		)
		(fp_line
			(start -4.533392 -2.249932)
			(end -4.533392 2.249932)
			(stroke
				(width 0.1524)
				(type default)
			)
			(layer "B.SilkS")
		)
		(fp_line
			(start 4.533392 -2.249932)
			(end -4.533392 -2.249932)
			(stroke
				(width 0.1524)
				(type default)
			)
			(layer "B.SilkS")
		)
		(fp_rect
			(start 5.39242 2.326132)
			(end 4.533392 -2.326132)
			(stroke
				(width 0)
				(type default)
			)
			(fill yes)
			(layer "B.SilkS")
		)
		(fp_line
			(start -3.750056 2.249932)
			(end 3.750056 2.249932)
			(stroke
				(width 0.1)
				(type default)
			)
			(layer "B.Fab")
		)
		(fp_line
			(start 3.750056 2.249932)
			(end 3.750056 -2.249932)
			(stroke
				(width 0.1)
				(type default)
			)
			(layer "B.Fab")
		)
		(fp_line
			(start -3.750056 -2.249932)
			(end -3.750056 2.249932)
			(stroke
				(width 0.1)
				(type default)
			)
			(layer "B.Fab")
		)
		(fp_line
			(start 3.750056 -2.249932)
			(end -3.750056 -2.249932)
			(stroke
				(width 0.1)
				(type default)
			)
			(layer "B.Fab")
		)
		(fp_text user "-"
			(at -4.416806 2.466848 270)
			(unlocked yes)
			(layer "B.SilkS")
			(effects
				(font
					(size 1.905 1.4224)
					(thickness 0.1524)
				)
				(justify left mirror)
			)
		)
		(fp_text user "+"
			(at 6.934454 0.61595 180)
			(unlocked yes)
			(layer "B.SilkS")
			(effects
				(font
					(size 1.905 1.4224)
					(thickness 0.1524)
				)
				(justify left mirror)
			)
		)
		(fp_text user "+"
			(at 6.322314 0.786384 180)
			(unlocked yes)
			(layer "B.Fab")
			(effects
				(font
					(size 1.905 1.4224)
					(thickness 0.1524)
				)
				(justify left mirror)
			)
		)
		(fp_text user "-"
			(at -4.8514 -0.14605 270)
			(unlocked yes)
			(layer "B.Fab")
			(effects
				(font
					(size 1.905 1.4224)
					(thickness 0.1524)
				)
				(justify left mirror)
			)
		)
		(pad "1" smd rect
			(at 3.199892 0 90)
			(size 2.413 2.8194)
			(layers "B.Cu" "B.Mask" "B.Paste")
			(net "PVDD11_S3_P0")
		)
		(pad "2" smd rect
			(at -3.199892 0 90)
			(size 2.413 2.8194)
			(layers "B.Cu" "B.Mask" "B.Paste")
			(net "GND")
		)
	)
)
